FILE_TYPE = CONNECTIVITY;
{Allegro Design Entry HDL 17.2-2016 S081 (4005846) 1/11/2022}
"PAGE_NUMBER" = 58;
0"NC";
1"M_H_CPU1_SA_CA<6:0>";
2"M_H_CPU1_SA_CS_N<3:0>";
3"M_H_CPU1_SA_DQS_DN<9:0>";
4"M_H_CPU1_SA_DQS_DP<9:0>";
5"M_H_CPU1_SB_CA<6:0>";
6"M_H_CPU1_SB_CS_N<3:0>";
7"M_H_CPU1_SB_DQS_DN<9:0>";
8"M_H_CPU1_SB_DQS_DP<9:0>";
9"M_H_CPU1_SB_CB<7:0>";
10"M_H_CPU1_SB_DQ<31:0>";
11"M_H_CPU1_SA_CB<7:0>";
12"M_H_CPU1_SA_DQ<31:0>";
13"M_H_CPU1_CLK_DP<1:0>";
14"M_H_CPU1_CLK_DN<1:0>";
15"M_H_CPU1_CLK_DN<1>";
16"M_H_CPU1_CLK_DN<0>";
17"M_H_CPU1_CLK_DP<1>";
18"M_H_CPU1_CLK_DP<0>";
19"M_H_CPU1_SA_DQ<31>";
20"M_H_CPU1_SA_DQ<30>";
21"M_H_CPU1_SA_DQ<29>";
22"M_H_CPU1_SA_DQ<28>";
23"M_H_CPU1_SA_DQ<27>";
24"M_H_CPU1_SA_DQ<26>";
25"M_H_CPU1_SA_DQ<25>";
26"M_H_CPU1_SA_DQ<24>";
27"M_H_CPU1_SA_DQ<23>";
28"M_H_CPU1_SA_DQ<22>";
29"M_H_CPU1_SA_DQ<21>";
30"M_H_CPU1_SA_DQ<20>";
31"M_H_CPU1_SA_DQ<19>";
32"M_H_CPU1_SA_DQ<18>";
33"M_H_CPU1_SA_DQ<17>";
34"M_H_CPU1_SA_DQ<16>";
35"M_H_CPU1_SA_DQ<15>";
36"M_H_CPU1_SA_DQ<14>";
37"M_H_CPU1_SA_DQ<13>";
38"M_H_CPU1_SA_DQ<12>";
39"M_H_CPU1_SA_DQ<11>";
40"M_H_CPU1_SA_DQ<10>";
41"M_H_CPU1_SA_DQ<9>";
42"M_H_CPU1_SA_DQ<8>";
43"M_H_CPU1_SA_DQ<7>";
44"M_H_CPU1_SA_DQ<6>";
45"M_H_CPU1_SA_DQ<5>";
46"M_H_CPU1_SA_DQ<4>";
47"M_H_CPU1_SA_DQ<3>";
48"M_H_CPU1_SA_DQ<2>";
49"M_H_CPU1_SA_DQ<1>";
50"M_H_CPU1_SA_DQ<0>";
51"M_H_CPU1_SA_CB<7>";
52"M_H_CPU1_SA_CB<6>";
53"M_H_CPU1_SA_CB<5>";
54"M_H_CPU1_SA_CB<4>";
55"M_H_CPU1_SA_CB<3>";
56"M_H_CPU1_SA_CB<2>";
57"M_H_CPU1_SA_CB<1>";
58"M_H_CPU1_SA_CB<0>";
59"M_H_CPU1_SB_DQ<31>";
60"M_H_CPU1_SB_DQ<30>";
61"M_H_CPU1_SB_DQ<29>";
62"M_H_CPU1_SB_DQ<28>";
63"M_H_CPU1_SB_DQ<27>";
64"M_H_CPU1_SB_DQ<26>";
65"M_H_CPU1_SB_DQ<25>";
66"M_H_CPU1_SB_DQ<24>";
67"M_H_CPU1_SB_DQ<23>";
68"M_H_CPU1_SB_DQ<22>";
69"M_H_CPU1_SB_DQ<21>";
70"M_H_CPU1_SB_DQ<20>";
71"M_H_CPU1_SB_DQ<19>";
72"M_H_CPU1_SB_DQ<18>";
73"M_H_CPU1_SB_DQ<17>";
74"M_H_CPU1_SB_DQ<16>";
75"M_H_CPU1_SB_DQ<15>";
76"M_H_CPU1_SB_DQ<14>";
77"M_H_CPU1_SB_DQ<13>";
78"M_H_CPU1_SB_DQ<12>";
79"M_H_CPU1_SB_DQ<11>";
80"M_H_CPU1_SB_DQ<10>";
81"M_H_CPU1_SB_DQ<9>";
82"M_H_CPU1_SB_DQ<8>";
83"M_H_CPU1_SB_DQ<7>";
84"M_H_CPU1_SB_DQ<6>";
85"M_H_CPU1_SB_DQ<5>";
86"M_H_CPU1_SB_DQ<4>";
87"M_H_CPU1_SB_DQ<3>";
88"M_H_CPU1_SB_DQ<2>";
89"M_H_CPU1_SB_DQ<1>";
90"M_H_CPU1_SB_DQ<0>";
91"M_H_CPU1_SB_CB<7>";
92"M_H_CPU1_SB_CB<6>";
93"M_H_CPU1_SB_CB<5>";
94"M_H_CPU1_SB_CB<4>";
95"M_H_CPU1_SB_CB<3>";
96"M_H_CPU1_SB_CB<2>";
97"M_H_CPU1_SB_CB<1>";
98"M_H_CPU1_SB_CB<0>";
99"M_H_CPU1_SB_PAR";
100"M_H_CPU1_SB_DQS_DP<0>";
101"M_H_CPU1_SB_DQS_DP<1>";
102"M_H_CPU1_SB_DQS_DP<2>";
103"M_H_CPU1_SB_DQS_DP<3>";
104"M_H_CPU1_SB_DQS_DP<4>";
105"M_H_CPU1_SB_DQS_DP<5>";
106"M_H_CPU1_SB_DQS_DP<6>";
107"M_H_CPU1_SB_DQS_DP<7>";
108"M_H_CPU1_SB_DQS_DP<8>";
109"M_H_CPU1_SB_DQS_DP<9>";
110"M_H_CPU1_SB_DQS_DN<0>";
111"M_H_CPU1_SB_DQS_DN<1>";
112"M_H_CPU1_SB_DQS_DN<2>";
113"M_H_CPU1_SB_DQS_DN<3>";
114"M_H_CPU1_SB_DQS_DN<4>";
115"M_H_CPU1_SB_DQS_DN<5>";
116"M_H_CPU1_SB_DQS_DN<6>";
117"M_H_CPU1_SB_DQS_DN<7>";
118"M_H_CPU1_SB_DQS_DN<8>";
119"M_H_CPU1_SB_DQS_DN<9>";
120"M_H_CPU1_SB_CS_N<0>";
121"M_H_CPU1_SB_CS_N<1>";
122"M_H_CPU1_SB_CS_N<2>";
123"M_H_CPU1_SB_CS_N<3>";
124"M_H_CPU1_SB_CA<0>";
125"M_H_CPU1_SB_CA<1>";
126"M_H_CPU1_SB_CA<2>";
127"M_H_CPU1_SB_CA<3>";
128"M_H_CPU1_SB_CA<4>";
129"M_H_CPU1_SB_CA<5>";
130"M_H_CPU1_SB_CA<6>";
131"M_H_CPU1_SA_PAR";
132"M_H_CPU1_SA_DQS_DP<0>";
133"M_H_CPU1_SA_DQS_DP<1>";
134"M_H_CPU1_SA_DQS_DP<2>";
135"M_H_CPU1_SA_DQS_DP<3>";
136"M_H_CPU1_SA_DQS_DP<4>";
137"M_H_CPU1_SA_DQS_DP<5>";
138"M_H_CPU1_SA_DQS_DP<6>";
139"M_H_CPU1_SA_DQS_DP<7>";
140"M_H_CPU1_SA_DQS_DP<8>";
141"M_H_CPU1_SA_DQS_DP<9>";
142"M_H_CPU1_SA_DQS_DN<0>";
143"M_H_CPU1_SA_DQS_DN<1>";
144"M_H_CPU1_SA_DQS_DN<2>";
145"M_H_CPU1_SA_DQS_DN<3>";
146"M_H_CPU1_SA_DQS_DN<4>";
147"M_H_CPU1_SA_DQS_DN<5>";
148"M_H_CPU1_SA_DQS_DN<6>";
149"M_H_CPU1_SA_DQS_DN<7>";
150"M_H_CPU1_SA_DQS_DN<8>";
151"M_H_CPU1_SA_DQS_DN<9>";
152"M_H_CPU1_SA_CS_N<0>";
153"M_H_CPU1_SA_CS_N<1>";
154"M_H_CPU1_SA_CS_N<2>";
155"M_H_CPU1_SA_CS_N<3>";
156"M_H_CPU1_SA_CA<0>";
157"M_H_CPU1_SA_CA<1>";
158"M_H_CPU1_SA_CA<2>";
159"M_H_CPU1_SA_CA<3>";
160"M_H_CPU1_SA_CA<4>";
161"M_H_CPU1_SA_CA<5>";
162"M_H_CPU1_SA_CA<6>";
163"M_H_CPU1_SB_RSP<0>";
164"M_H_CPU1_SB_RSP<1>";
165"M_H_CPU1_SA_RSP<0>";
166"M_H_CPU1_SA_RSP<1>";
167"M_H_CPU1_ALERT_N";
%"TAP"
"1","(-650,-75)","2","standard","I10";
;
CDS_LIB"standard"
BODY_TYPE"PLUMBING"
HDL_TAP"TRUE";
"B \NAC \NWC"9;
"S \NAC"
BN"1"97;
%"TAP"
"1","(2775,725)","0","standard","I100";
;
CDS_LIB"standard"
BODY_TYPE"PLUMBING"
HDL_TAP"TRUE";
"B \NAC \NWC"5;
"S \NAC"
BN"0"124;
%"TAP"
"1","(2775,825)","0","standard","I101";
;
CDS_LIB"standard"
BODY_TYPE"PLUMBING"
HDL_TAP"TRUE";
"B \NAC \NWC"5;
"S \NAC"
BN"2"126;
%"TAP"
"1","(2775,775)","0","standard","I102";
;
CDS_LIB"standard"
BODY_TYPE"PLUMBING"
HDL_TAP"TRUE";
"B \NAC \NWC"5;
"S \NAC"
BN"1"125;
%"TAP"
"1","(2775,925)","0","standard","I103";
;
CDS_LIB"standard"
BODY_TYPE"PLUMBING"
HDL_TAP"TRUE";
"B \NAC \NWC"5;
"S \NAC"
BN"4"128;
%"TAP"
"1","(2775,1025)","0","standard","I104";
;
CDS_LIB"standard"
BODY_TYPE"PLUMBING"
HDL_TAP"TRUE";
"B \NAC \NWC"5;
"S \NAC"
BN"6"130;
%"TAP"
"1","(2775,875)","0","standard","I105";
;
CDS_LIB"standard"
BODY_TYPE"PLUMBING"
HDL_TAP"TRUE";
"B \NAC \NWC"5;
"S \NAC"
BN"3"127;
%"TAP"
"1","(2775,975)","0","standard","I106";
;
CDS_LIB"standard"
BODY_TYPE"PLUMBING"
HDL_TAP"TRUE";
"B \NAC \NWC"5;
"S \NAC"
BN"5"129;
%"TAP"
"1","(2775,1225)","0","standard","I107";
;
CDS_LIB"standard"
BODY_TYPE"PLUMBING"
HDL_TAP"TRUE";
"B \NAC \NWC"1;
"S \NAC"
BN"0"156;
%"TAP"
"1","(2775,1325)","0","standard","I108";
;
CDS_LIB"standard"
BODY_TYPE"PLUMBING"
HDL_TAP"TRUE";
"B \NAC \NWC"1;
"S \NAC"
BN"2"158;
%"TAP"
"1","(2775,1275)","0","standard","I109";
;
CDS_LIB"standard"
BODY_TYPE"PLUMBING"
HDL_TAP"TRUE";
"B \NAC \NWC"1;
"S \NAC"
BN"1"157;
%"TAP"
"1","(-650,-125)","2","standard","I11";
;
CDS_LIB"standard"
BODY_TYPE"PLUMBING"
HDL_TAP"TRUE";
"B \NAC \NWC"9;
"S \NAC"
BN"0"98;
%"TAP"
"1","(-650,25)","2","standard","I12";
;
CDS_LIB"standard"
BODY_TYPE"PLUMBING"
HDL_TAP"TRUE";
"B \NAC \NWC"9;
"S \NAC"
BN"3"95;
%"TAP"
"1","(2775,1425)","0","standard","I120";
;
CDS_LIB"standard"
BODY_TYPE"PLUMBING"
HDL_TAP"TRUE";
"B \NAC \NWC"1;
"S \NAC"
BN"4"160;
%"TAP"
"1","(2775,1525)","0","standard","I121";
;
CDS_LIB"standard"
BODY_TYPE"PLUMBING"
HDL_TAP"TRUE";
"B \NAC \NWC"1;
"S \NAC"
BN"6"162;
%"TAP"
"1","(2775,1475)","0","standard","I122";
;
CDS_LIB"standard"
BODY_TYPE"PLUMBING"
HDL_TAP"TRUE";
"B \NAC \NWC"1;
"S \NAC"
BN"5"161;
%"TAP"
"1","(2775,1375)","0","standard","I123";
;
CDS_LIB"standard"
BODY_TYPE"PLUMBING"
HDL_TAP"TRUE";
"B \NAC \NWC"1;
"S \NAC"
BN"3"159;
%"TAP"
"1","(2775,1775)","0","standard","I124";
;
CDS_LIB"standard"
BODY_TYPE"PLUMBING"
HDL_TAP"TRUE";
"B \NAC \NWC"7;
"S \NAC"
BN"2"112;
%"TAP"
"1","(2775,1825)","0","standard","I125";
;
CDS_LIB"standard"
BODY_TYPE"PLUMBING"
HDL_TAP"TRUE";
"B \NAC \NWC"7;
"S \NAC"
BN"3"113;
%"TAP"
"1","(2775,1875)","0","standard","I126";
;
CDS_LIB"standard"
BODY_TYPE"PLUMBING"
HDL_TAP"TRUE";
"B \NAC \NWC"7;
"S \NAC"
BN"4"114;
%"TAP"
"1","(2775,1725)","0","standard","I127";
;
CDS_LIB"standard"
BODY_TYPE"PLUMBING"
HDL_TAP"TRUE";
"B \NAC \NWC"7;
"S \NAC"
BN"1"111;
%"TAP"
"1","(2775,1675)","0","standard","I128";
;
CDS_LIB"standard"
BODY_TYPE"PLUMBING"
HDL_TAP"TRUE";
"B \NAC \NWC"7;
"S \NAC"
BN"0"110;
%"TAP"
"1","(2775,2125)","0","standard","I129";
;
CDS_LIB"standard"
BODY_TYPE"PLUMBING"
HDL_TAP"TRUE";
"B \NAC \NWC"7;
"S \NAC"
BN"9"119;
%"TAP"
"1","(-650,-25)","2","standard","I13";
;
CDS_LIB"standard"
BODY_TYPE"PLUMBING"
HDL_TAP"TRUE";
"B \NAC \NWC"9;
"S \NAC"
BN"2"96;
%"TAP"
"1","(2775,2075)","0","standard","I130";
;
CDS_LIB"standard"
BODY_TYPE"PLUMBING"
HDL_TAP"TRUE";
"B \NAC \NWC"7;
"S \NAC"
BN"8"118;
%"TAP"
"1","(2775,2025)","0","standard","I131";
;
CDS_LIB"standard"
BODY_TYPE"PLUMBING"
HDL_TAP"TRUE";
"B \NAC \NWC"7;
"S \NAC"
BN"7"117;
%"TAP"
"1","(2775,1925)","0","standard","I132";
;
CDS_LIB"standard"
BODY_TYPE"PLUMBING"
HDL_TAP"TRUE";
"B \NAC \NWC"7;
"S \NAC"
BN"5"115;
%"TAP"
"1","(2775,1975)","0","standard","I133";
;
CDS_LIB"standard"
BODY_TYPE"PLUMBING"
HDL_TAP"TRUE";
"B \NAC \NWC"7;
"S \NAC"
BN"6"116;
%"TAP"
"1","(2775,2275)","0","standard","I134";
;
CDS_LIB"standard"
BODY_TYPE"PLUMBING"
HDL_TAP"TRUE";
"B \NAC \NWC"8;
"S \NAC"
BN"1"101;
%"TAP"
"1","(2775,2325)","0","standard","I135";
;
CDS_LIB"standard"
BODY_TYPE"PLUMBING"
HDL_TAP"TRUE";
"B \NAC \NWC"8;
"S \NAC"
BN"2"102;
%"TAP"
"1","(2775,2375)","0","standard","I136";
;
CDS_LIB"standard"
BODY_TYPE"PLUMBING"
HDL_TAP"TRUE";
"B \NAC \NWC"8;
"S \NAC"
BN"3"103;
%"TAP"
"1","(2775,2225)","0","standard","I137";
;
CDS_LIB"standard"
BODY_TYPE"PLUMBING"
HDL_TAP"TRUE";
"B \NAC \NWC"8;
"S \NAC"
BN"0"100;
%"TAP"
"1","(2775,2625)","0","standard","I138";
;
CDS_LIB"standard"
BODY_TYPE"PLUMBING"
HDL_TAP"TRUE";
"B \NAC \NWC"8;
"S \NAC"
BN"8"108;
%"TAP"
"1","(2775,2575)","0","standard","I139";
;
CDS_LIB"standard"
BODY_TYPE"PLUMBING"
HDL_TAP"TRUE";
"B \NAC \NWC"8;
"S \NAC"
BN"7"107;
%"TAP"
"1","(-650,75)","2","standard","I14";
;
CDS_LIB"standard"
BODY_TYPE"PLUMBING"
HDL_TAP"TRUE";
"B \NAC \NWC"9;
"S \NAC"
BN"4"94;
%"TAP"
"1","(2775,2475)","0","standard","I140";
;
CDS_LIB"standard"
BODY_TYPE"PLUMBING"
HDL_TAP"TRUE";
"B \NAC \NWC"8;
"S \NAC"
BN"5"105;
%"TAP"
"1","(2775,2425)","0","standard","I141";
;
CDS_LIB"standard"
BODY_TYPE"PLUMBING"
HDL_TAP"TRUE";
"B \NAC \NWC"8;
"S \NAC"
BN"4"104;
%"TAP"
"1","(2775,2525)","0","standard","I142";
;
CDS_LIB"standard"
BODY_TYPE"PLUMBING"
HDL_TAP"TRUE";
"B \NAC \NWC"8;
"S \NAC"
BN"6"106;
%"TAP"
"1","(2775,2675)","0","standard","I143";
;
CDS_LIB"standard"
BODY_TYPE"PLUMBING"
HDL_TAP"TRUE";
"B \NAC \NWC"8;
"S \NAC"
BN"9"109;
%"TAP"
"1","(2775,2875)","0","standard","I144";
;
CDS_LIB"standard"
BODY_TYPE"PLUMBING"
HDL_TAP"TRUE";
"B \NAC \NWC"3;
"S \NAC"
BN"1"143;
%"TAP"
"1","(2775,2825)","0","standard","I145";
;
CDS_LIB"standard"
BODY_TYPE"PLUMBING"
HDL_TAP"TRUE";
"B \NAC \NWC"3;
"S \NAC"
BN"0"142;
%"TAP"
"1","(2775,3075)","0","standard","I146";
;
CDS_LIB"standard"
BODY_TYPE"PLUMBING"
HDL_TAP"TRUE";
"B \NAC \NWC"3;
"S \NAC"
BN"5"147;
%"TAP"
"1","(2775,3125)","0","standard","I147";
;
CDS_LIB"standard"
BODY_TYPE"PLUMBING"
HDL_TAP"TRUE";
"B \NAC \NWC"3;
"S \NAC"
BN"6"148;
%"TAP"
"1","(2775,2975)","0","standard","I148";
;
CDS_LIB"standard"
BODY_TYPE"PLUMBING"
HDL_TAP"TRUE";
"B \NAC \NWC"3;
"S \NAC"
BN"3"145;
%"TAP"
"1","(2775,2925)","0","standard","I149";
;
CDS_LIB"standard"
BODY_TYPE"PLUMBING"
HDL_TAP"TRUE";
"B \NAC \NWC"3;
"S \NAC"
BN"2"144;
%"TAP"
"1","(-650,175)","2","standard","I15";
;
CDS_LIB"standard"
BODY_TYPE"PLUMBING"
HDL_TAP"TRUE";
"B \NAC \NWC"9;
"S \NAC"
BN"6"92;
%"TAP"
"1","(2775,3025)","0","standard","I150";
;
CDS_LIB"standard"
BODY_TYPE"PLUMBING"
HDL_TAP"TRUE";
"B \NAC \NWC"3;
"S \NAC"
BN"4"146;
%"TAP"
"1","(2775,3275)","0","standard","I151";
;
CDS_LIB"standard"
BODY_TYPE"PLUMBING"
HDL_TAP"TRUE";
"B \NAC \NWC"3;
"S \NAC"
BN"9"151;
%"TAP"
"1","(2775,3225)","0","standard","I152";
;
CDS_LIB"standard"
BODY_TYPE"PLUMBING"
HDL_TAP"TRUE";
"B \NAC \NWC"3;
"S \NAC"
BN"8"150;
%"TAP"
"1","(2775,3375)","0","standard","I153";
;
CDS_LIB"standard"
BODY_TYPE"PLUMBING"
HDL_TAP"TRUE";
"B \NAC \NWC"4;
"S \NAC"
BN"0"132;
%"TAP"
"1","(2775,3175)","0","standard","I154";
;
CDS_LIB"standard"
BODY_TYPE"PLUMBING"
HDL_TAP"TRUE";
"B \NAC \NWC"3;
"S \NAC"
BN"7"149;
%"TAP"
"1","(2775,3575)","0","standard","I159";
;
CDS_LIB"standard"
BODY_TYPE"PLUMBING"
HDL_TAP"TRUE";
"B \NAC \NWC"4;
"S \NAC"
BN"4"136;
%"TAP"
"1","(-650,125)","2","standard","I16";
;
CDS_LIB"standard"
BODY_TYPE"PLUMBING"
HDL_TAP"TRUE";
"B \NAC \NWC"9;
"S \NAC"
BN"5"93;
%"TAP"
"1","(2775,3625)","0","standard","I160";
;
CDS_LIB"standard"
BODY_TYPE"PLUMBING"
HDL_TAP"TRUE";
"B \NAC \NWC"4;
"S \NAC"
BN"5"137;
%"TAP"
"1","(2775,3675)","0","standard","I161";
;
CDS_LIB"standard"
BODY_TYPE"PLUMBING"
HDL_TAP"TRUE";
"B \NAC \NWC"4;
"S \NAC"
BN"6"138;
%"TAP"
"1","(2775,3475)","0","standard","I162";
;
CDS_LIB"standard"
BODY_TYPE"PLUMBING"
HDL_TAP"TRUE";
"B \NAC \NWC"4;
"S \NAC"
BN"2"134;
%"TAP"
"1","(2775,3525)","0","standard","I163";
;
CDS_LIB"standard"
BODY_TYPE"PLUMBING"
HDL_TAP"TRUE";
"B \NAC \NWC"4;
"S \NAC"
BN"3"135;
%"TAP"
"1","(2775,3425)","0","standard","I164";
;
CDS_LIB"standard"
BODY_TYPE"PLUMBING"
HDL_TAP"TRUE";
"B \NAC \NWC"4;
"S \NAC"
BN"1"133;
%"TAP"
"1","(2775,3725)","0","standard","I165";
;
CDS_LIB"standard"
BODY_TYPE"PLUMBING"
HDL_TAP"TRUE";
"B \NAC \NWC"4;
"S \NAC"
BN"7"139;
%"TAP"
"1","(2775,3825)","0","standard","I166";
;
CDS_LIB"standard"
BODY_TYPE"PLUMBING"
HDL_TAP"TRUE";
"B \NAC \NWC"4;
"S \NAC"
BN"9"141;
%"TAP"
"1","(2775,3775)","0","standard","I167";
;
CDS_LIB"standard"
BODY_TYPE"PLUMBING"
HDL_TAP"TRUE";
"B \NAC \NWC"4;
"S \NAC"
BN"8"140;
%"TAP"
"1","(-650,275)","2","standard","I17";
;
CDS_LIB"standard"
BODY_TYPE"PLUMBING"
HDL_TAP"TRUE";
"B \NAC \NWC"10;
"S \NAC"
BN"0"90;
%"TAP"
"1","(-650,225)","2","standard","I18";
;
CDS_LIB"standard"
BODY_TYPE"PLUMBING"
HDL_TAP"TRUE";
"B \NAC \NWC"9;
"S \NAC"
BN"7"91;
%"TAP"
"1","(-650,325)","2","standard","I19";
;
CDS_LIB"standard"
BODY_TYPE"PLUMBING"
HDL_TAP"TRUE";
"B \NAC \NWC"10;
"S \NAC"
BN"1"89;
%"SOCKET4677_AZIF0045P001C01CS"
"15","(1075,1725)","0","pure_quanta","I20";
;
PART_NUMBER"DGA^7000023"
PART_TYPE"SMLF"
MATERIAL"IO"
VALUE"SOCKET4677_AZIF0045-P001C01CS"
$LOCATION"U1"
CDS_LIB"pure_quanta"
NEEDS_NO_SIZE"TRUE"
CDS_LMAN_SYM_OUTLINE"-1100,2250,1050,-2250"
CDS_LOCATION"U1"
$SEC"15"
CDS_SEC"15";
"DDR7_SB_PAR"
$PN"DR39"99;
"DDR7_SB_ECC0"
$PN"DC35"98;
"DDR7_SB_ECC1"
$PN"DD34"97;
"DDR7_SB_ECC2"
$PN"DG35"96;
"DDR7_SB_ECC3"
$PN"DF34"95;
"DDR7_SB_ECC4"
$PN"DF38"94;
"DDR7_SB_ECC5"
$PN"DG37"93;
"DDR7_SB_ECC6"
$PN"DD38"92;
"DDR7_SB_ECC7"
$PN"DC37"91;
"DDR7_SB_DQS_DP0"
$PN"DB30"100;
"DDR7_SB_DQS_DP1"
$PN"DB24"101;
"DDR7_SB_DQS_DP2"
$PN"DJ21"102;
"DDR7_SB_DQS_DP3"
$PN"DD18"103;
"DDR7_SB_DQS_DP4"
$PN"DF36"104;
"DDR7_SB_DQS_DP5"
$PN"DF30"105;
"DDR7_SB_DQS_DP6"
$PN"DF24"106;
"DDR7_SB_DQS_DP7"
$PN"DN21"107;
"DDR7_SB_DQS_DP8"
$PN"DH18"108;
"DDR7_SB_DQS_DP9"
$PN"DB36"109;
"DDR7_SB_DQS_DN0 \B"
$PN"DD30"110;
"DDR7_SB_DQS_DN1 \B"
$PN"DD24"111;
"DDR7_SB_DQS_DN2 \B"
$PN"DL21"112;
"DDR7_SB_DQS_DN3 \B"
$PN"DB18"113;
"DDR7_SB_DQS_DN4 \B"
$PN"DH36"114;
"DDR7_SB_DQS_DN5 \B"
$PN"DH30"115;
"DDR7_SB_DQS_DN6 \B"
$PN"DH24"116;
"DDR7_SB_DQS_DN7 \B"
$PN"DR21"117;
"DDR7_SB_DQS_DN8 \B"
$PN"DF18"118;
"DDR7_SB_DQS_DN9 \B"
$PN"DD36"119;
"DDR7_SB_DQ0"
$PN"DD32"90;
"DDR7_SB_DQ1"
$PN"DC31"89;
"DDR7_SB_DQ2"
$PN"DF32"88;
"DDR7_SB_DQ3"
$PN"DG31"87;
"DDR7_SB_DQ4"
$PN"DC29"86;
"DDR7_SB_DQ5"
$PN"DF28"85;
"DDR7_SB_DQ6"
$PN"DG29"84;
"DDR7_SB_DQ7"
$PN"DD28"83;
"DDR7_SB_DQ8"
$PN"DD26"82;
"DDR7_SB_DQ9"
$PN"DC25"81;
"DDR7_SB_DQ10"
$PN"DF26"80;
"DDR7_SB_DQ11"
$PN"DG25"79;
"DDR7_SB_DQ12"
$PN"DC23"78;
"DDR7_SB_DQ13"
$PN"DD22"77;
"DDR7_SB_DQ14"
$PN"DG23"76;
"DDR7_SB_DQ15"
$PN"DF22"75;
"DDR7_SB_DQ16"
$PN"DL23"74;
"DDR7_SB_DQ17"
$PN"DK22"73;
"DDR7_SB_DQ18"
$PN"DN23"72;
"DDR7_SB_DQ19"
$PN"DP22"71;
"DDR7_SB_DQ20"
$PN"DK20"70;
"DDR7_SB_DQ21"
$PN"DL19"69;
"DDR7_SB_DQ22"
$PN"DP20"68;
"DDR7_SB_DQ23"
$PN"DN19"67;
"DDR7_SB_DQ24"
$PN"DD20"66;
"DDR7_SB_DQ25"
$PN"DC19"65;
"DDR7_SB_DQ26"
$PN"DF20"64;
"DDR7_SB_DQ27"
$PN"DG19"63;
"DDR7_SB_DQ28"
$PN"DG17"62;
"DDR7_SB_DQ29"
$PN"DA17"61;
"DDR7_SB_DQ30"
$PN"DJ17"60;
"DDR7_SB_DQ31"
$PN"DC17"59;
"DDR7_SB_CS_N0 \B"
$PN"DL37"120;
"DDR7_SB_CS_N1 \B"
$PN"DN37"121;
"DDR7_SB_CS_N2 \B"
$PN"DK38"122;
"DDR7_SB_CS_N3 \B"
$PN"DP38"123;
"DDR7_SB_CA0"
$PN"DF40"124;
"DDR7_SB_CA1"
$PN"DG41"125;
"DDR7_SB_CA2"
$PN"DL41"126;
"DDR7_SB_CA3"
$PN"DN41"127;
"DDR7_SB_CA4"
$PN"DK40"128;
"DDR7_SB_CA5"
$PN"DP40"129;
"DDR7_SB_CA6"
$PN"DJ39"130;
"DDR7_SA_PAR"
$PN"DD40"131;
"DDR7_SA_ECC0"
$PN"DD57"58;
"DDR7_SA_ECC1"
$PN"DC56"57;
"DDR7_SA_ECC2"
$PN"DF57"56;
"DDR7_SA_ECC3"
$PN"DG56"55;
"DDR7_SA_ECC4"
$PN"DC54"54;
"DDR7_SA_ECC5"
$PN"DD53"53;
"DDR7_SA_ECC6"
$PN"DG54"52;
"DDR7_SA_ECC7"
$PN"DF53"51;
"DDR7_SA_DQS_DP0"
$PN"DL76"132;
"DDR7_SA_DQS_DP1"
$PN"DD73"133;
"DDR7_SA_DQS_DP2"
$PN"DB67"134;
"DDR7_SA_DQS_DP3"
$PN"DB61"135;
"DDR7_SA_DQS_DP4"
$PN"DB55"136;
"DDR7_SA_DQS_DP5"
$PN"DN76"137;
"DDR7_SA_DQS_DP6"
$PN"DF73"138;
"DDR7_SA_DQS_DP7"
$PN"DF67"139;
"DDR7_SA_DQS_DP8"
$PN"DF61"140;
"DDR7_SA_DQS_DP9"
$PN"DF55"141;
"DDR7_SA_DQS_DN0 \B"
$PN"DJ76"142;
"DDR7_SA_DQS_DN1 \B"
$PN"DB73"143;
"DDR7_SA_DQS_DN2 \B"
$PN"DD67"144;
"DDR7_SA_DQS_DN3 \B"
$PN"DD61"145;
"DDR7_SA_DQS_DN4 \B"
$PN"DD55"146;
"DDR7_SA_DQS_DN5 \B"
$PN"DR76"147;
"DDR7_SA_DQS_DN6 \B"
$PN"DH73"148;
"DDR7_SA_DQS_DN7 \B"
$PN"DH67"149;
"DDR7_SA_DQS_DN8 \B"
$PN"DH61"150;
"DDR7_SA_DQS_DN9 \B"
$PN"DH55"151;
"DDR7_SA_DQ0"
$PN"DY79"50;
"DDR7_SA_DQ1"
$PN"DT77"49;
"DDR7_SA_DQ2"
$PN"DW78"48;
"DDR7_SA_DQ3"
$PN"DP77"47;
"DDR7_SA_DQ4"
$PN"DK75"46;
"DDR7_SA_DQ5"
$PN"DL74"45;
"DDR7_SA_DQ6"
$PN"DP75"44;
"DDR7_SA_DQ7"
$PN"DN74"43;
"DDR7_SA_DQ8"
$PN"DD75"42;
"DDR7_SA_DQ9"
$PN"DC74"41;
"DDR7_SA_DQ10"
$PN"DF75"40;
"DDR7_SA_DQ11"
$PN"DG74"39;
"DDR7_SA_DQ12"
$PN"DC72"38;
"DDR7_SA_DQ13"
$PN"DD71"37;
"DDR7_SA_DQ14"
$PN"DG72"36;
"DDR7_SA_DQ15"
$PN"DF71"35;
"DDR7_SA_DQ16"
$PN"DD69"34;
"DDR7_SA_DQ17"
$PN"DC68"33;
"DDR7_SA_DQ18"
$PN"DF69"32;
"DDR7_SA_DQ19"
$PN"DG68"31;
"DDR7_SA_DQ20"
$PN"DC66"30;
"DDR7_SA_DQ21"
$PN"DD65"29;
"DDR7_SA_DQ22"
$PN"DG66"28;
"DDR7_SA_DQ23"
$PN"DF65"27;
"DDR7_SA_DQ24"
$PN"DD63"26;
"DDR7_SA_DQ25"
$PN"DC62"25;
"DDR7_SA_DQ26"
$PN"DF63"24;
"DDR7_SA_DQ27"
$PN"DG62"23;
"DDR7_SA_DQ28"
$PN"DC60"22;
"DDR7_SA_DQ29"
$PN"DD59"21;
"DDR7_SA_DQ30"
$PN"DG60"20;
"DDR7_SA_DQ31"
$PN"DF59"19;
"DDR7_SA_CS_N0 \B"
$PN"DF51"152;
"DDR7_SA_CS_N1 \B"
$PN"DG50"153;
"DDR7_SA_CS_N2 \B"
$PN"DD51"154;
"DDR7_SA_CS_N3 \B"
$PN"DC50"155;
"DDR7_SA_CA0"
$PN"DB49"156;
"DDR7_SA_CA1"
$PN"DH49"157;
"DDR7_SA_CA2"
$PN"DC48"158;
"DDR7_SA_CA3"
$PN"DG48"159;
"DDR7_SA_CA4"
$PN"DD47"160;
"DDR7_SA_CA5"
$PN"DF47"161;
"DDR7_SA_CA6"
$PN"DC41"162;
"DDR7_CLK_DP0"
$PN"DF42"18;
"DDR7_CLK_DP1"
$PN"DB42"17;
"DDR7_CLK_DN0 \B"
$PN"DH42"16;
"DDR7_CLK_DN1 \B"
$PN"DD42"15;
"DDR7_B_RSP0"
$PN"EE48"163;
"DDR7_B_RSP1"
$PN"ED47"164;
"DDR7_A_RSP0"
$PN"EG48"165;
"DDR7_A_RSP1"
$PN"EH47"166;
"DDR7_ALERT_N \B"
$PN"CY51"167;
%"TAP"
"1","(-650,425)","2","standard","I21";
;
CDS_LIB"standard"
BODY_TYPE"PLUMBING"
HDL_TAP"TRUE";
"B \NAC \NWC"10;
"S \NAC"
BN"3"87;
%"TAP"
"1","(-650,375)","2","standard","I22";
;
CDS_LIB"standard"
BODY_TYPE"PLUMBING"
HDL_TAP"TRUE";
"B \NAC \NWC"10;
"S \NAC"
BN"2"88;
%"TAP"
"1","(-650,475)","2","standard","I23";
;
CDS_LIB"standard"
BODY_TYPE"PLUMBING"
HDL_TAP"TRUE";
"B \NAC \NWC"10;
"S \NAC"
BN"4"86;
%"TAP"
"1","(-650,575)","2","standard","I24";
;
CDS_LIB"standard"
BODY_TYPE"PLUMBING"
HDL_TAP"TRUE";
"B \NAC \NWC"10;
"S \NAC"
BN"6"84;
%"TAP"
"1","(-650,525)","2","standard","I25";
;
CDS_LIB"standard"
BODY_TYPE"PLUMBING"
HDL_TAP"TRUE";
"B \NAC \NWC"10;
"S \NAC"
BN"5"85;
%"TAP"
"1","(-650,675)","2","standard","I26";
;
CDS_LIB"standard"
BODY_TYPE"PLUMBING"
HDL_TAP"TRUE";
"B \NAC \NWC"10;
"S \NAC"
BN"8"82;
%"TAP"
"1","(-650,625)","2","standard","I27";
;
CDS_LIB"standard"
BODY_TYPE"PLUMBING"
HDL_TAP"TRUE";
"B \NAC \NWC"10;
"S \NAC"
BN"7"83;
%"TAP"
"1","(-650,725)","2","standard","I28";
;
CDS_LIB"standard"
BODY_TYPE"PLUMBING"
HDL_TAP"TRUE";
"B \NAC \NWC"10;
"S \NAC"
BN"9"81;
%"TAP"
"1","(-650,775)","2","standard","I29";
;
CDS_LIB"standard"
BODY_TYPE"PLUMBING"
HDL_TAP"TRUE";
"B \NAC \NWC"10;
"S \NAC"
BN"10"80;
%"TAP"
"1","(-650,825)","2","standard","I30";
;
CDS_LIB"standard"
BODY_TYPE"PLUMBING"
HDL_TAP"TRUE";
"B \NAC \NWC"10;
"S \NAC"
BN"11"79;
%"TAP"
"1","(-650,925)","2","standard","I31";
;
CDS_LIB"standard"
BODY_TYPE"PLUMBING"
HDL_TAP"TRUE";
"B \NAC \NWC"10;
"S \NAC"
BN"13"77;
%"TAP"
"1","(-650,875)","2","standard","I32";
;
CDS_LIB"standard"
BODY_TYPE"PLUMBING"
HDL_TAP"TRUE";
"B \NAC \NWC"10;
"S \NAC"
BN"12"78;
%"TAP"
"1","(-650,975)","2","standard","I33";
;
CDS_LIB"standard"
BODY_TYPE"PLUMBING"
HDL_TAP"TRUE";
"B \NAC \NWC"10;
"S \NAC"
BN"14"76;
%"TAP"
"1","(-650,1025)","2","standard","I34";
;
CDS_LIB"standard"
BODY_TYPE"PLUMBING"
HDL_TAP"TRUE";
"B \NAC \NWC"10;
"S \NAC"
BN"15"75;
%"TAP"
"1","(-650,1075)","2","standard","I35";
;
CDS_LIB"standard"
BODY_TYPE"PLUMBING"
HDL_TAP"TRUE";
"B \NAC \NWC"10;
"S \NAC"
BN"16"74;
%"TAP"
"1","(-650,1175)","2","standard","I36";
;
CDS_LIB"standard"
BODY_TYPE"PLUMBING"
HDL_TAP"TRUE";
"B \NAC \NWC"10;
"S \NAC"
BN"18"72;
%"TAP"
"1","(-650,1125)","2","standard","I37";
;
CDS_LIB"standard"
BODY_TYPE"PLUMBING"
HDL_TAP"TRUE";
"B \NAC \NWC"10;
"S \NAC"
BN"17"73;
%"TAP"
"1","(-650,1225)","2","standard","I38";
;
CDS_LIB"standard"
BODY_TYPE"PLUMBING"
HDL_TAP"TRUE";
"B \NAC \NWC"10;
"S \NAC"
BN"19"71;
%"TAP"
"1","(-650,1325)","2","standard","I39";
;
CDS_LIB"standard"
BODY_TYPE"PLUMBING"
HDL_TAP"TRUE";
"B \NAC \NWC"10;
"S \NAC"
BN"21"69;
%"TAP"
"1","(-650,1275)","2","standard","I40";
;
CDS_LIB"standard"
BODY_TYPE"PLUMBING"
HDL_TAP"TRUE";
"B \NAC \NWC"10;
"S \NAC"
BN"20"70;
%"TAP"
"1","(-650,1375)","2","standard","I41";
;
CDS_LIB"standard"
BODY_TYPE"PLUMBING"
HDL_TAP"TRUE";
"B \NAC \NWC"10;
"S \NAC"
BN"22"68;
%"TAP"
"1","(-650,1425)","2","standard","I42";
;
CDS_LIB"standard"
BODY_TYPE"PLUMBING"
HDL_TAP"TRUE";
"B \NAC \NWC"10;
"S \NAC"
BN"23"67;
%"TAP"
"1","(-650,1475)","2","standard","I43";
;
CDS_LIB"standard"
BODY_TYPE"PLUMBING"
HDL_TAP"TRUE";
"B \NAC \NWC"10;
"S \NAC"
BN"24"66;
%"TAP"
"1","(-650,1525)","2","standard","I44";
;
CDS_LIB"standard"
BODY_TYPE"PLUMBING"
HDL_TAP"TRUE";
"B \NAC \NWC"10;
"S \NAC"
BN"25"65;
%"TAP"
"1","(-650,1575)","2","standard","I45";
;
CDS_LIB"standard"
BODY_TYPE"PLUMBING"
HDL_TAP"TRUE";
"B \NAC \NWC"10;
"S \NAC"
BN"26"64;
%"TAP"
"1","(-650,1625)","2","standard","I46";
;
CDS_LIB"standard"
BODY_TYPE"PLUMBING"
HDL_TAP"TRUE";
"B \NAC \NWC"10;
"S \NAC"
BN"27"63;
%"TAP"
"1","(-650,1675)","2","standard","I47";
;
CDS_LIB"standard"
BODY_TYPE"PLUMBING"
HDL_TAP"TRUE";
"B \NAC \NWC"10;
"S \NAC"
BN"28"62;
%"TAP"
"1","(-650,1725)","2","standard","I48";
;
CDS_LIB"standard"
BODY_TYPE"PLUMBING"
HDL_TAP"TRUE";
"B \NAC \NWC"10;
"S \NAC"
BN"29"61;
%"TAP"
"1","(-650,1825)","2","standard","I49";
;
CDS_LIB"standard"
BODY_TYPE"PLUMBING"
HDL_TAP"TRUE";
"B \NAC \NWC"10;
"S \NAC"
BN"31"59;
%"TAP"
"1","(-650,1775)","2","standard","I50";
;
CDS_LIB"standard"
BODY_TYPE"PLUMBING"
HDL_TAP"TRUE";
"B \NAC \NWC"10;
"S \NAC"
BN"30"60;
%"TAP"
"1","(-650,1875)","2","standard","I51";
;
CDS_LIB"standard"
BODY_TYPE"PLUMBING"
HDL_TAP"TRUE";
"B \NAC \NWC"11;
"S \NAC"
BN"0"58;
%"TAP"
"1","(-650,1975)","2","standard","I52";
;
CDS_LIB"standard"
BODY_TYPE"PLUMBING"
HDL_TAP"TRUE";
"B \NAC \NWC"11;
"S \NAC"
BN"2"56;
%"TAP"
"1","(-650,1925)","2","standard","I53";
;
CDS_LIB"standard"
BODY_TYPE"PLUMBING"
HDL_TAP"TRUE";
"B \NAC \NWC"11;
"S \NAC"
BN"1"57;
%"TAP"
"1","(-650,2075)","2","standard","I54";
;
CDS_LIB"standard"
BODY_TYPE"PLUMBING"
HDL_TAP"TRUE";
"B \NAC \NWC"11;
"S \NAC"
BN"4"54;
%"TAP"
"1","(-650,2025)","2","standard","I55";
;
CDS_LIB"standard"
BODY_TYPE"PLUMBING"
HDL_TAP"TRUE";
"B \NAC \NWC"11;
"S \NAC"
BN"3"55;
%"TAP"
"1","(-650,2125)","2","standard","I56";
;
CDS_LIB"standard"
BODY_TYPE"PLUMBING"
HDL_TAP"TRUE";
"B \NAC \NWC"11;
"S \NAC"
BN"5"53;
%"TAP"
"1","(-650,2225)","2","standard","I57";
;
CDS_LIB"standard"
BODY_TYPE"PLUMBING"
HDL_TAP"TRUE";
"B \NAC \NWC"11;
"S \NAC"
BN"7"51;
%"TAP"
"1","(-650,2175)","2","standard","I58";
;
CDS_LIB"standard"
BODY_TYPE"PLUMBING"
HDL_TAP"TRUE";
"B \NAC \NWC"11;
"S \NAC"
BN"6"52;
%"TAP"
"1","(-650,2325)","2","standard","I59";
;
CDS_LIB"standard"
BODY_TYPE"PLUMBING"
HDL_TAP"TRUE";
"B \NAC \NWC"12;
"S \NAC"
BN"1"49;
%"TAP"
"1","(-650,-325)","2","standard","I6";
;
CDS_LIB"standard"
BODY_TYPE"PLUMBING"
HDL_TAP"TRUE";
"B \NAC \NWC"14;
"S \NAC"
BN"1"15;
%"TAP"
"1","(-650,2275)","2","standard","I60";
;
CDS_LIB"standard"
BODY_TYPE"PLUMBING"
HDL_TAP"TRUE";
"B \NAC \NWC"12;
"S \NAC"
BN"0"50;
%"TAP"
"1","(-650,2375)","2","standard","I61";
;
CDS_LIB"standard"
BODY_TYPE"PLUMBING"
HDL_TAP"TRUE";
"B \NAC \NWC"12;
"S \NAC"
BN"2"48;
%"TAP"
"1","(-650,2475)","2","standard","I62";
;
CDS_LIB"standard"
BODY_TYPE"PLUMBING"
HDL_TAP"TRUE";
"B \NAC \NWC"12;
"S \NAC"
BN"4"46;
%"TAP"
"1","(-650,2425)","2","standard","I63";
;
CDS_LIB"standard"
BODY_TYPE"PLUMBING"
HDL_TAP"TRUE";
"B \NAC \NWC"12;
"S \NAC"
BN"3"47;
%"TAP"
"1","(-650,2525)","2","standard","I64";
;
CDS_LIB"standard"
BODY_TYPE"PLUMBING"
HDL_TAP"TRUE";
"B \NAC \NWC"12;
"S \NAC"
BN"5"45;
%"TAP"
"1","(-650,2625)","2","standard","I65";
;
CDS_LIB"standard"
BODY_TYPE"PLUMBING"
HDL_TAP"TRUE";
"B \NAC \NWC"12;
"S \NAC"
BN"7"43;
%"TAP"
"1","(-650,2575)","2","standard","I66";
;
CDS_LIB"standard"
BODY_TYPE"PLUMBING"
HDL_TAP"TRUE";
"B \NAC \NWC"12;
"S \NAC"
BN"6"44;
%"TAP"
"1","(-650,2725)","2","standard","I67";
;
CDS_LIB"standard"
BODY_TYPE"PLUMBING"
HDL_TAP"TRUE";
"B \NAC \NWC"12;
"S \NAC"
BN"9"41;
%"TAP"
"1","(-650,2675)","2","standard","I68";
;
CDS_LIB"standard"
BODY_TYPE"PLUMBING"
HDL_TAP"TRUE";
"B \NAC \NWC"12;
"S \NAC"
BN"8"42;
%"TAP"
"1","(-650,2775)","2","standard","I69";
;
CDS_LIB"standard"
BODY_TYPE"PLUMBING"
HDL_TAP"TRUE";
"B \NAC \NWC"12;
"S \NAC"
BN"10"40;
%"TAP"
"1","(-650,-375)","2","standard","I7";
;
CDS_LIB"standard"
BODY_TYPE"PLUMBING"
HDL_TAP"TRUE";
"B \NAC \NWC"14;
"S \NAC"
BN"0"16;
%"TAP"
"1","(-650,2825)","2","standard","I70";
;
CDS_LIB"standard"
BODY_TYPE"PLUMBING"
HDL_TAP"TRUE";
"B \NAC \NWC"12;
"S \NAC"
BN"11"39;
%"TAP"
"1","(-650,2875)","2","standard","I71";
;
CDS_LIB"standard"
BODY_TYPE"PLUMBING"
HDL_TAP"TRUE";
"B \NAC \NWC"12;
"S \NAC"
BN"12"38;
%"TAP"
"1","(-650,2975)","2","standard","I72";
;
CDS_LIB"standard"
BODY_TYPE"PLUMBING"
HDL_TAP"TRUE";
"B \NAC \NWC"12;
"S \NAC"
BN"14"36;
%"TAP"
"1","(-650,2925)","2","standard","I73";
;
CDS_LIB"standard"
BODY_TYPE"PLUMBING"
HDL_TAP"TRUE";
"B \NAC \NWC"12;
"S \NAC"
BN"13"37;
%"TAP"
"1","(-650,3025)","2","standard","I74";
;
CDS_LIB"standard"
BODY_TYPE"PLUMBING"
HDL_TAP"TRUE";
"B \NAC \NWC"12;
"S \NAC"
BN"15"35;
%"TAP"
"1","(-650,3075)","2","standard","I75";
;
CDS_LIB"standard"
BODY_TYPE"PLUMBING"
HDL_TAP"TRUE";
"B \NAC \NWC"12;
"S \NAC"
BN"16"34;
%"TAP"
"1","(-650,3125)","2","standard","I76";
;
CDS_LIB"standard"
BODY_TYPE"PLUMBING"
HDL_TAP"TRUE";
"B \NAC \NWC"12;
"S \NAC"
BN"17"33;
%"TAP"
"1","(-650,3225)","2","standard","I77";
;
CDS_LIB"standard"
BODY_TYPE"PLUMBING"
HDL_TAP"TRUE";
"B \NAC \NWC"12;
"S \NAC"
BN"19"31;
%"TAP"
"1","(-650,3175)","2","standard","I78";
;
CDS_LIB"standard"
BODY_TYPE"PLUMBING"
HDL_TAP"TRUE";
"B \NAC \NWC"12;
"S \NAC"
BN"18"32;
%"TAP"
"1","(-650,3275)","2","standard","I79";
;
CDS_LIB"standard"
BODY_TYPE"PLUMBING"
HDL_TAP"TRUE";
"B \NAC \NWC"12;
"S \NAC"
BN"20"30;
%"TAP"
"1","(-650,-275)","2","standard","I8";
;
CDS_LIB"standard"
BODY_TYPE"PLUMBING"
HDL_TAP"TRUE";
"B \NAC \NWC"13;
"S \NAC"
BN"0"18;
%"TAP"
"1","(-650,3375)","2","standard","I80";
;
CDS_LIB"standard"
BODY_TYPE"PLUMBING"
HDL_TAP"TRUE";
"B \NAC \NWC"12;
"S \NAC"
BN"22"28;
%"TAP"
"1","(-650,3325)","2","standard","I81";
;
CDS_LIB"standard"
BODY_TYPE"PLUMBING"
HDL_TAP"TRUE";
"B \NAC \NWC"12;
"S \NAC"
BN"21"29;
%"TAP"
"1","(-650,3475)","2","standard","I83";
;
CDS_LIB"standard"
BODY_TYPE"PLUMBING"
HDL_TAP"TRUE";
"B \NAC \NWC"12;
"S \NAC"
BN"24"26;
%"TAP"
"1","(-650,3425)","2","standard","I84";
;
CDS_LIB"standard"
BODY_TYPE"PLUMBING"
HDL_TAP"TRUE";
"B \NAC \NWC"12;
"S \NAC"
BN"23"27;
%"TAP"
"1","(-650,3525)","2","standard","I85";
;
CDS_LIB"standard"
BODY_TYPE"PLUMBING"
HDL_TAP"TRUE";
"B \NAC \NWC"12;
"S \NAC"
BN"25"25;
%"TAP"
"1","(-650,3625)","2","standard","I86";
;
CDS_LIB"standard"
BODY_TYPE"PLUMBING"
HDL_TAP"TRUE";
"B \NAC \NWC"12;
"S \NAC"
BN"27"23;
%"TAP"
"1","(-650,3575)","2","standard","I87";
;
CDS_LIB"standard"
BODY_TYPE"PLUMBING"
HDL_TAP"TRUE";
"B \NAC \NWC"12;
"S \NAC"
BN"26"24;
%"TAP"
"1","(-650,3675)","2","standard","I88";
;
CDS_LIB"standard"
BODY_TYPE"PLUMBING"
HDL_TAP"TRUE";
"B \NAC \NWC"12;
"S \NAC"
BN"28"22;
%"TAP"
"1","(-650,3725)","2","standard","I89";
;
CDS_LIB"standard"
BODY_TYPE"PLUMBING"
HDL_TAP"TRUE";
"B \NAC \NWC"12;
"S \NAC"
BN"29"21;
%"TAP"
"1","(-650,-225)","2","standard","I9";
;
CDS_LIB"standard"
BODY_TYPE"PLUMBING"
HDL_TAP"TRUE";
"B \NAC \NWC"13;
"S \NAC"
BN"1"17;
%"TAP"
"1","(-650,3775)","2","standard","I90";
;
CDS_LIB"standard"
BODY_TYPE"PLUMBING"
HDL_TAP"TRUE";
"B \NAC \NWC"12;
"S \NAC"
BN"30"20;
%"TAP"
"1","(-650,3825)","2","standard","I91";
;
CDS_LIB"standard"
BODY_TYPE"PLUMBING"
HDL_TAP"TRUE";
"B \NAC \NWC"12;
"S \NAC"
BN"31"19;
%"TAP"
"1","(2775,75)","0","standard","I92";
;
CDS_LIB"standard"
BODY_TYPE"PLUMBING"
HDL_TAP"TRUE";
"B \NAC \NWC"6;
"S \NAC"
BN"0"120;
%"TAP"
"1","(2775,225)","0","standard","I93";
;
CDS_LIB"standard"
BODY_TYPE"PLUMBING"
HDL_TAP"TRUE";
"B \NAC \NWC"6;
"S \NAC"
BN"3"123;
%"TAP"
"1","(2775,125)","0","standard","I94";
;
CDS_LIB"standard"
BODY_TYPE"PLUMBING"
HDL_TAP"TRUE";
"B \NAC \NWC"6;
"S \NAC"
BN"1"121;
%"TAP"
"1","(2775,175)","0","standard","I95";
;
CDS_LIB"standard"
BODY_TYPE"PLUMBING"
HDL_TAP"TRUE";
"B \NAC \NWC"6;
"S \NAC"
BN"2"122;
%"TAP"
"1","(2775,375)","0","standard","I96";
;
CDS_LIB"standard"
BODY_TYPE"PLUMBING"
HDL_TAP"TRUE";
"B \NAC \NWC"2;
"S \NAC"
BN"0"152;
%"TAP"
"1","(2775,525)","0","standard","I97";
;
CDS_LIB"standard"
BODY_TYPE"PLUMBING"
HDL_TAP"TRUE";
"B \NAC \NWC"2;
"S \NAC"
BN"3"155;
%"TAP"
"1","(2775,475)","0","standard","I98";
;
CDS_LIB"standard"
BODY_TYPE"PLUMBING"
HDL_TAP"TRUE";
"B \NAC \NWC"2;
"S \NAC"
BN"2"154;
%"TAP"
"1","(2775,425)","0","standard","I99";
;
CDS_LIB"standard"
BODY_TYPE"PLUMBING"
HDL_TAP"TRUE";
"B \NAC \NWC"2;
"S \NAC"
BN"1"153;
END.
